(kicad_pcb
	(version 20240108)
	(generator "pcbnew")
	(generator_version "8.0")
	(general
		(thickness 1.62)
		(legacy_teardrops no)
	)
	(paper "A4")
	(title_block
		(title "Jetson Orin Baseboard")
		(date "2025-03-12")
		(rev "1.3.4")
		(company "Antmicro Ltd")
		(comment 1 "www.antmicro.com")
		(comment 9 "footprints 511-514 of 677")
	)
	(layers
		(0 "F.Cu" signal)
		(1 "In1.Cu" signal)
		(2 "In2.Cu" signal)
		(3 "In3.Cu" signal)
		(4 "In4.Cu" jumper)
		(5 "In5.Cu" signal)
		(6 "In6.Cu" signal)
		(31 "B.Cu" signal)
		(32 "B.Adhes" user "B.Adhesive")
		(33 "F.Adhes" user "F.Adhesive")
		(34 "B.Paste" user)
		(35 "F.Paste" user)
		(36 "B.SilkS" user "B.Silkscreen")
		(37 "F.SilkS" user "F.Silkscreen")
		(38 "B.Mask" user)
		(39 "F.Mask" user)
		(40 "Dwgs.User" user "User.Drawings")
		(41 "Cmts.User" user "User.Comments")
		(42 "Eco1.User" user "User.Eco1")
		(43 "Eco2.User" user "User.Eco2")
		(44 "Edge.Cuts" user)
		(45 "Margin" user)
		(46 "B.CrtYd" user "B.Courtyard")
		(47 "F.CrtYd" user "F.Courtyard")
		(48 "B.Fab" user)
		(49 "F.Fab" user)
	)
	(footprint "antmicro-footprints:SOT-523"
		(layer "B.Cu")
		(at 71.4 71.2)
		(property "Reference" "Q8"
			(at 0.77 -1.03 0)
			(layer "B.SilkS")
			(effects
				(font
					(size 0.7 0.7)
					(thickness 0.15)
				)
				(justify left bottom mirror)
			)
		)
		(property "Value" "PJE138K"
			(at 0.1 -1.824 180)
			(layer "B.Fab")
			(effects
				(font
					(size 0.7 0.7)
					(thickness 0.15)
				)
				(justify left bottom mirror)
			)
		)
		(property "Footprint" "antmicro-footprints:SOT-523"
			(at 0 0 0)
			(layer "F.Fab")
			(hide yes)
			(effects
				(font
					(size 1.27 1.27)
					(thickness 0.15)
				)
			)
		)
		(property "Datasheet" "https://www.mouser.com/datasheet/2/1057/PJE138K-1876698.pdf"
			(at 0 0 0)
			(layer "F.Fab")
			(hide yes)
			(effects
				(font
					(size 1.27 1.27)
					(thickness 0.15)
				)
			)
		)
		(property "Author" "Antmicro"
			(at 0 0 0)
			(layer "B.Fab")
			(hide yes)
			(effects
				(font
					(size 1 1)
					(thickness 0.15)
				)
				(justify mirror)
			)
		)
		(property "License" "Apache-2.0"
			(at 0 0 0)
			(layer "B.Fab")
			(hide yes)
			(effects
				(font
					(size 1 1)
					(thickness 0.15)
				)
				(justify mirror)
			)
		)
		(property "MPN" "PJE138K_R1_00001"
			(at 0 0 0)
			(layer "B.Fab")
			(hide yes)
			(effects
				(font
					(size 1 1)
					(thickness 0.15)
				)
				(justify mirror)
			)
		)
		(property "Manufacturer" "PANJIT"
			(at 0 0 0)
			(layer "B.Fab")
			(hide yes)
			(effects
				(font
					(size 1 1)
					(thickness 0.15)
				)
				(justify mirror)
			)
		)
		(sheetname "Supply")
		(sheetfile "supply.kicad_sch")
		(attr smd)
		(fp_line
			(start -0.927 0.351)
			(end -0.927 0.051)
			(stroke
				(width 0.15)
				(type solid)
			)
			(layer "B.SilkS")
		)
		(fp_line
			(start -0.725 0.551)
			(end -0.927 0.351)
			(stroke
				(width 0.15)
				(type solid)
			)
			(layer "B.SilkS")
		)
		(fp_line
			(start -0.277 0.551)
			(end -0.725 0.551)
			(stroke
				(width 0.15)
				(type solid)
			)
			(layer "B.SilkS")
		)
		(fp_line
			(start -0.277 0.75)
			(end -0.277 0.551)
			(stroke
				(width 0.15)
				(type solid)
			)
			(layer "B.SilkS")
		)
		(fp_circle
			(center -0.9652 -0.9652)
			(end -0.9152 -0.9652)
			(stroke
				(width 0.15)
				(type solid)
			)
			(fill solid)
			(layer "B.SilkS")
		)
		(fp_line
			(start -1.12 -1.15)
			(end -1.12 1.16)
			(stroke
				(width 0.05)
				(type solid)
			)
			(layer "B.CrtYd")
		)
		(fp_line
			(start 1.1 -1.15)
			(end -1.12 -1.15)
			(stroke
				(width 0.05)
				(type solid)
			)
			(layer "B.CrtYd")
		)
		(fp_line
			(start 1.1 -1.15)
			(end 1.1 1.16)
			(stroke
				(width 0.05)
				(type solid)
			)
			(layer "B.CrtYd")
		)
		(fp_line
			(start 1.1 1.16)
			(end -1.12 1.16)
			(stroke
				(width 0.05)
				(type solid)
			)
			(layer "B.CrtYd")
		)
		(fp_line
			(start -0.802 -0.424)
			(end -0.802 0.276)
			(stroke
				(width 0.15)
				(type solid)
			)
			(layer "B.Fab")
		)
		(fp_line
			(start -0.802 -0.424)
			(end 0.8 -0.424)
			(stroke
				(width 0.15)
				(type solid)
			)
			(layer "B.Fab")
		)
		(fp_line
			(start -0.802 0.276)
			(end -0.652 0.425)
			(stroke
				(width 0.15)
				(type solid)
			)
			(layer "B.Fab")
		)
		(fp_line
			(start -0.652 0.425)
			(end 0.8 0.425)
			(stroke
				(width 0.15)
				(type solid)
			)
			(layer "B.Fab")
		)
		(fp_line
			(start 0.8 -0.424)
			(end 0.8 0.425)
			(stroke
				(width 0.15)
				(type solid)
			)
			(layer "B.Fab")
		)
		(fp_circle
			(center -0.9652 -0.9652)
			(end -0.9144 -0.9652)
			(stroke
				(width 0.15)
				(type solid)
			)
			(fill none)
			(layer "B.Fab")
		)
		(fp_text user "${REFERENCE}"
			(at -1.12 -3.824 180)
			(layer "B.Fab")
			(hide yes)
			(effects
				(font
					(size 0.7 0.7)
					(thickness 0.15)
				)
				(justify left bottom mirror)
			)
		)
		(fp_text user "Author: Antmicro"
			(at -1.12 -6.224 180)
			(layer "B.Fab")
			(hide yes)
			(effects
				(font
					(size 0.7 0.7)
					(thickness 0.15)
				)
				(justify left bottom mirror)
			)
		)
		(fp_text user "License: Apache-2.0"
			(at -1.12 -5.024 180)
			(layer "B.Fab")
			(hide yes)
			(effects
				(font
					(size 0.7 0.7)
					(thickness 0.15)
				)
				(justify left bottom mirror)
			)
		)
		(pad "1" smd rect
			(at -0.5 -0.65)
			(size 0.4 0.51)
			(layers "B.Cu" "B.Paste" "B.Mask")
			(net 179 "Net-(D61-A)")
			(pinfunction "G")
			(pintype "passive")
		)
		(pad "2" smd rect
			(at 0.498 -0.65)
			(size 0.4 0.51)
			(layers "B.Cu" "B.Paste" "B.Mask")
			(net 1 "GND")
			(pinfunction "S")
			(pintype "passive")
		)
		(pad "3" smd rect
			(at 0 0.652)
			(size 0.4 0.51)
			(layers "B.Cu" "B.Paste" "B.Mask")
			(net 86 "~{RESET}")
			(pinfunction "D")
			(pintype "passive")
		)
	)
	(footprint "antmicro-footprints:C_0402_1005Metric"
		(layer "B.Cu")
		(at 67.68 78.71 180)
		(descr "Capacitor SMD 0402")
		(tags "capacitor SMD 0402")
		(property "Reference" "C41"
			(at -16.09 -3.48 0)
			(layer "B.SilkS")
			(effects
				(font
					(size 0.7 0.7)
					(thickness 0.15)
				)
				(justify left bottom mirror)
			)
		)
		(property "Value" "C_100n_0402"
			(at 0 -1.4 0)
			(layer "B.Fab")
			(effects
				(font
					(size 0.7 0.7)
					(thickness 0.15)
				)
				(justify left bottom mirror)
			)
		)
		(property "Footprint" "antmicro-footprints:C_0402_1005Metric"
			(at 0 0 180)
			(layer "F.Fab")
			(hide yes)
			(effects
				(font
					(size 1.27 1.27)
					(thickness 0.15)
				)
			)
		)
		(property "Datasheet" "https://www.murata.com/products/productdetail?partno=GRM155R61H104KE14%23"
			(at 0 0 180)
			(layer "F.Fab")
			(hide yes)
			(effects
				(font
					(size 1.27 1.27)
					(thickness 0.15)
				)
			)
		)
		(property "Author" "Antmicro"
			(at 135.36 157.42 0)
			(layer "B.Fab")
			(hide yes)
			(effects
				(font
					(size 1 1)
					(thickness 0.15)
				)
				(justify mirror)
			)
		)
		(property "Dielectric" "X5R"
			(at 135.36 157.42 0)
			(layer "B.Fab")
			(hide yes)
			(effects
				(font
					(size 1 1)
					(thickness 0.15)
				)
				(justify mirror)
			)
		)
		(property "License" "Apache-2.0"
			(at 135.36 157.42 0)
			(layer "B.Fab")
			(hide yes)
			(effects
				(font
					(size 1 1)
					(thickness 0.15)
				)
				(justify mirror)
			)
		)
		(property "MPN" "GRM155R61H104KE14D"
			(at 135.36 157.42 0)
			(layer "B.Fab")
			(hide yes)
			(effects
				(font
					(size 1 1)
					(thickness 0.15)
				)
				(justify mirror)
			)
		)
		(property "Manufacturer" "Murata"
			(at 135.36 157.42 0)
			(layer "B.Fab")
			(hide yes)
			(effects
				(font
					(size 1 1)
					(thickness 0.15)
				)
				(justify mirror)
			)
		)
		(property "Val" "100n"
			(at 135.36 157.42 0)
			(layer "B.Fab")
			(hide yes)
			(effects
				(font
					(size 1 1)
					(thickness 0.15)
				)
				(justify mirror)
			)
		)
		(property "Voltage" "50V"
			(at 135.36 157.42 0)
			(layer "B.Fab")
			(hide yes)
			(effects
				(font
					(size 1 1)
					(thickness 0.15)
				)
				(justify mirror)
			)
		)
		(sheetname "SoM")
		(sheetfile "som.kicad_sch")
		(attr smd)
		(fp_rect
			(start -0.925 0.47)
			(end 0.925 -0.47)
			(stroke
				(width 0.05)
				(type default)
			)
			(fill none)
			(layer "B.CrtYd")
		)
		(fp_line
			(start 0.504 0.25)
			(end -0.494 0.25)
			(stroke
				(width 0.15)
				(type solid)
			)
			(layer "B.Fab")
		)
		(fp_line
			(start 0.504 -0.248)
			(end 0.504 0.25)
			(stroke
				(width 0.15)
				(type solid)
			)
			(layer "B.Fab")
		)
		(fp_line
			(start -0.494 0.25)
			(end -0.494 -0.248)
			(stroke
				(width 0.15)
				(type solid)
			)
			(layer "B.Fab")
		)
		(fp_line
			(start -0.494 -0.248)
			(end 0.504 -0.248)
			(stroke
				(width 0.15)
				(type solid)
			)
			(layer "B.Fab")
		)
		(fp_text user "${REFERENCE}"
			(at -0.932 -3.168 0)
			(layer "B.Fab")
			(hide yes)
			(effects
				(font
					(size 0.7 0.7)
					(thickness 0.15)
				)
				(justify left bottom mirror)
			)
		)
		(fp_text user "License: Apache-2.0"
			(at -0.932 -5.17 0)
			(layer "B.Fab")
			(hide yes)
			(effects
				(font
					(size 0.7 0.7)
					(thickness 0.15)
				)
				(justify left bottom mirror)
			)
		)
		(fp_text user "Author: Antmicro"
			(at -0.932 -4.17 0)
			(layer "B.Fab")
			(hide yes)
			(effects
				(font
					(size 0.7 0.7)
					(thickness 0.15)
				)
				(justify left bottom mirror)
			)
		)
		(pad "1" smd roundrect
			(at -0.48 0 180)
			(size 0.59 0.64)
			(layers "B.Cu" "B.Paste" "B.Mask")
			(roundrect_rratio 0.25)
			(net 1 "GND")
			(pintype "passive")
		)
		(pad "2" smd roundrect
			(at 0.48 0 180)
			(size 0.59 0.64)
			(layers "B.Cu" "B.Paste" "B.Mask")
			(roundrect_rratio 0.25)
			(net 87 "+3V3")
			(pintype "passive")
		)
	)
	(footprint "antmicro-footprints:R_0402_1005Metric"
		(layer "B.Cu")
		(at 88.2 105.1 180)
		(descr "Resistor SMD 0402")
		(tags "resistor SMD 0402")
		(property "Reference" "R194"
			(at 0.7 0.05 0)
			(layer "B.SilkS")
			(effects
				(font
					(size 0.6 0.6)
					(thickness 0.15)
				)
				(justify left bottom mirror)
			)
		)
		(property "Value" "R_10k_0402"
			(at 0 -1.4 0)
			(layer "B.Fab")
			(effects
				(font
					(size 0.7 0.7)
					(thickness 0.15)
				)
				(justify left bottom mirror)
			)
		)
		(property "Footprint" "antmicro-footprints:R_0402_1005Metric"
			(at 0 0 180)
			(layer "F.Fab")
			(hide yes)
			(effects
				(font
					(size 1.27 1.27)
					(thickness 0.15)
				)
			)
		)
		(property "Datasheet" "https://www.bourns.com/docs/product-datasheets/cr.pdf"
			(at 0 0 180)
			(layer "F.Fab")
			(hide yes)
			(effects
				(font
					(size 1.27 1.27)
					(thickness 0.15)
				)
			)
		)
		(property "Author" "Antmicro"
			(at 176.4 210.2 0)
			(layer "B.Fab")
			(hide yes)
			(effects
				(font
					(size 1 1)
					(thickness 0.15)
				)
				(justify mirror)
			)
		)
		(property "License" "Apache-2.0"
			(at 176.4 210.2 0)
			(layer "B.Fab")
			(hide yes)
			(effects
				(font
					(size 1 1)
					(thickness 0.15)
				)
				(justify mirror)
			)
		)
		(property "MPN" "CR0402-FX-1002GLF"
			(at 176.4 210.2 0)
			(layer "B.Fab")
			(hide yes)
			(effects
				(font
					(size 1 1)
					(thickness 0.15)
				)
				(justify mirror)
			)
		)
		(property "Manufacturer" "Bourns"
			(at 176.4 210.2 0)
			(layer "B.Fab")
			(hide yes)
			(effects
				(font
					(size 1 1)
					(thickness 0.15)
				)
				(justify mirror)
			)
		)
		(property "Tolerance" "1%"
			(at 176.4 210.2 0)
			(layer "B.Fab")
			(hide yes)
			(effects
				(font
					(size 1 1)
					(thickness 0.15)
				)
				(justify mirror)
			)
		)
		(property "Val" "10k"
			(at 176.4 210.2 0)
			(layer "B.Fab")
			(hide yes)
			(effects
				(font
					(size 1 1)
					(thickness 0.15)
				)
				(justify mirror)
			)
		)
		(sheetname "CSI")
		(sheetfile "csi.kicad_sch")
		(attr smd exclude_from_pos_files exclude_from_bom dnp)
		(fp_rect
			(start -0.925 0.47)
			(end 0.925 -0.47)
			(stroke
				(width 0.05)
				(type default)
			)
			(fill none)
			(layer "B.CrtYd")
		)
		(fp_rect
			(start -0.5 0.25)
			(end 0.5 -0.25)
			(stroke
				(width 0.15)
				(type solid)
			)
			(fill none)
			(layer "B.Fab")
		)
		(fp_text user "${REFERENCE}"
			(at -0.95 -3.168 0)
			(layer "B.Fab")
			(hide yes)
			(effects
				(font
					(size 0.7 0.7)
					(thickness 0.15)
				)
				(justify left bottom mirror)
			)
		)
		(fp_text user "License: Apache-2.0"
			(at -0.95 -5.169 0)
			(layer "B.Fab")
			(hide yes)
			(effects
				(font
					(size 0.7 0.7)
					(thickness 0.15)
				)
				(justify left bottom mirror)
			)
		)
		(fp_text user "Author: Antmicro"
			(at -0.95 -4.169 0)
			(layer "B.Fab")
			(hide yes)
			(effects
				(font
					(size 0.7 0.7)
					(thickness 0.15)
				)
				(justify left bottom mirror)
			)
		)
		(pad "1" smd roundrect
			(at -0.48 0 180)
			(size 0.59 0.64)
			(layers "B.Cu" "B.Paste" "B.Mask")
			(roundrect_rratio 0.25)
			(net 338 "CSIB_PEN")
			(pintype "passive")
		)
		(pad "2" smd roundrect
			(at 0.48 0 180)
			(size 0.59 0.64)
			(layers "B.Cu" "B.Paste" "B.Mask")
			(roundrect_rratio 0.25)
			(net 87 "+3V3")
			(pintype "passive")
		)
	)
	(footprint "antmicro-footprints:SC-74-6_1.5x2.9mm_P0.95mm"
		(layer "B.Cu")
		(at 109 88.02 180)
		(tags "sc74 sc-74 sot23-6 sot457 tsop6 tsop-6")
		(property "Reference" "U3"
			(at -2.52 1.97 0)
			(layer "B.SilkS")
			(effects
				(font
					(size 0.7 0.7)
					(thickness 0.15)
				)
				(justify left bottom mirror)
			)
		)
		(property "Value" "74LVC2G07_SOT457"
			(at -2 -2.999 0)
			(layer "B.Fab")
			(effects
				(font
					(size 0.7 0.7)
					(thickness 0.15)
				)
				(justify left bottom mirror)
			)
		)
		(property "Footprint" "antmicro-footprints:SC-74-6_1.5x2.9mm_P0.95mm"
			(at 0 0 180)
			(layer "F.Fab")
			(hide yes)
			(effects
				(font
					(size 1.27 1.27)
					(thickness 0.15)
				)
			)
		)
		(property "Datasheet" "https://www.tme.eu/Document/2ad9356043a4952b9021ef50162f8c34/74LVC2G07.pdf"
			(at 0 0 180)
			(layer "F.Fab")
			(hide yes)
			(effects
				(font
					(size 1.27 1.27)
					(thickness 0.15)
				)
			)
		)
		(property "Author" "Antmicro"
			(at 218 176.04 0)
			(layer "B.Fab")
			(hide yes)
			(effects
				(font
					(size 1 1)
					(thickness 0.15)
				)
				(justify mirror)
			)
		)
		(property "License" "Apache-2.0"
			(at 218 176.04 0)
			(layer "B.Fab")
			(hide yes)
			(effects
				(font
					(size 1 1)
					(thickness 0.15)
				)
				(justify mirror)
			)
		)
		(property "MPN" "74LVC2G07GV,125"
			(at 218 176.04 0)
			(layer "B.Fab")
			(hide yes)
			(effects
				(font
					(size 1 1)
					(thickness 0.15)
				)
				(justify mirror)
			)
		)
		(property "Manufacturer" "Nexperia"
			(at 218 176.04 0)
			(layer "B.Fab")
			(hide yes)
			(effects
				(font
					(size 1 1)
					(thickness 0.15)
				)
				(justify mirror)
			)
		)
		(property ki_fp_filters "SG-74 SOT23-6 TSOP6 SOT457")
		(sheetname "M.2")
		(sheetfile "m-2.kicad_sch")
		(attr smd exclude_from_pos_files exclude_from_bom dnp)
		(fp_circle
			(center -1.11 1.454)
			(end -1.06 1.454)
			(stroke
				(width 0.15)
				(type solid)
			)
			(fill solid)
			(layer "B.SilkS")
		)
		(fp_rect
			(start -1.7 1.7)
			(end 1.7 -1.7)
			(stroke
				(width 0.05)
				(type solid)
			)
			(fill none)
			(layer "B.CrtYd")
		)
		(fp_line
			(start 1.22 1.422)
			(end 1.22 -1.372)
			(stroke
				(width 0.15)
				(type solid)
			)
			(layer "B.Fab")
		)
		(fp_line
			(start 1.22 -1.372)
			(end -1.167 -1.372)
			(stroke
				(width 0.15)
				(type solid)
			)
			(layer "B.Fab")
		)
		(fp_line
			(start -0.76 1.422)
			(end 1.22 1.422)
			(stroke
				(width 0.15)
				(type solid)
			)
			(layer "B.Fab")
		)
		(fp_line
			(start -1.167 -1.372)
			(end -1.269 -1.372)
			(stroke
				(width 0.15)
				(type solid)
			)
			(layer "B.Fab")
		)
		(fp_line
			(start -1.269 0.915)
			(end -0.76 1.422)
			(stroke
				(width 0.15)
				(type solid)
			)
			(layer "B.Fab")
		)
		(fp_line
			(start -1.269 -1.372)
			(end -1.269 0.915)
			(stroke
				(width 0.15)
				(type solid)
			)
			(layer "B.Fab")
		)
		(fp_text user "Author: Antmicro"
			(at -2.12 -4.999 0)
			(layer "B.Fab")
			(hide yes)
			(effects
				(font
					(size 0.7 0.7)
					(thickness 0.15)
				)
				(justify left bottom mirror)
			)
		)
		(fp_text user "License: Apache-2.0"
			(at -2.12 -6.199 0)
			(layer "B.Fab")
			(hide yes)
			(effects
				(font
					(size 0.7 0.7)
					(thickness 0.15)
				)
				(justify left bottom mirror)
			)
		)
		(fp_text user "${REFERENCE}"
			(at -2.12 -7.399 0)
			(layer "B.Fab")
			(hide yes)
			(effects
				(font
					(size 0.7 0.7)
					(thickness 0.15)
				)
				(justify left bottom mirror)
			)
		)
		(pad "1" smd roundrect
			(at -1.2 0.95 180)
			(size 0.8 0.55)
			(layers "B.Cu" "B.Paste" "B.Mask")
			(roundrect_rratio 0.15)
			(net 248 "/M.2/~{M2_M_CLKREQ0}")
			(pintype "input")
		)
		(pad "2" smd roundrect
			(at -1.2 0 180)
			(size 0.8 0.55)
			(layers "B.Cu" "B.Paste" "B.Mask")
			(roundrect_rratio 0.15)
			(net 1 "GND")
			(pinfunction "GND")
			(pintype "power_in")
		)
		(pad "3" smd roundrect
			(at -1.2 -0.95 180)
			(size 0.8 0.55)
			(layers "B.Cu" "B.Paste" "B.Mask")
			(roundrect_rratio 0.15)
			(net 247 "/M.2/~{M2_M_PERST}")
			(pintype "input")
		)
		(pad "4" smd roundrect
			(at 1.2 -0.95 180)
			(size 0.8 0.55)
			(layers "B.Cu" "B.Paste" "B.Mask")
			(roundrect_rratio 0.15)
			(net 455 "PCIE0_RST*")
			(pintype "output")
		)
		(pad "5" smd roundrect
			(at 1.2 0 180)
			(size 0.8 0.55)
			(layers "B.Cu" "B.Paste" "B.Mask")
			(roundrect_rratio 0.15)
			(net 87 "+3V3")
			(pinfunction "V_{CC}")
			(pintype "power_in")
		)
		(pad "6" smd roundrect
			(at 1.2 0.95 180)
			(size 0.8 0.55)
			(layers "B.Cu" "B.Paste" "B.Mask")
			(roundrect_rratio 0.15)
			(net 454 "PCIE0_CLKREQ*")
			(pintype "output")
		)
	)
)
